(kicad_pcb
	(version 20260206)
	(generator "pcbnew")
	(generator_version "10.0")
	(general
		(thickness 1.6)
		(legacy_teardrops no)
	)
	(paper "A4")
	(title_block
		(title "04192023_DAF0TMB3IC0_F0TG_MB_C_brd_V02_OCP.brd")
		(comment 1 "Grand Teton / footprints 6259-6265 of 8354")
	)
	(layers
		(0 "F.Cu" signal "TOP")
		(4 "In1.Cu" signal "GND")
		(6 "In2.Cu" signal "IN1")
		(8 "In3.Cu" signal "GND1")
		(10 "In4.Cu" signal "IN2")
		(12 "In5.Cu" signal "GND2")
		(14 "In6.Cu" signal "IN3")
		(16 "In7.Cu" signal "GND3")
		(18 "In8.Cu" signal "VCC")
		(20 "In9.Cu" signal "VCC1")
		(22 "In10.Cu" signal "GND4")
		(24 "In11.Cu" signal "IN4")
		(26 "In12.Cu" signal "GND5")
		(28 "In13.Cu" signal "IN5")
		(30 "In14.Cu" signal "GND6")
		(32 "In15.Cu" signal "IN6")
		(34 "In16.Cu" signal "GND7")
		(2 "B.Cu" signal "BOTTOM")
		(9 "F.Adhes" user "F.Adhesive")
		(11 "B.Adhes" user "B.Adhesive")
		(13 "F.Paste" user "Package Geometry/Pastemask Top")
		(15 "B.Paste" user "Package Geometry/Pastemask Bottom")
		(5 "F.SilkS" user "Ref Des/Silkscreen Top")
		(7 "B.SilkS" user "Ref Des/Silkscreen Bottom")
		(1 "F.Mask" user "Board Geometry/Soldermask Top")
		(3 "B.Mask" user "Board Geometry/Soldermask Bottom")
		(17 "Dwgs.User" user "User.Drawings")
		(19 "Cmts.User" user "User.Comments")
		(21 "Eco1.User" user "User.Eco1")
		(23 "Eco2.User" user "User.Eco2")
		(25 "Edge.Cuts" user "Board Geometry/Outline")
		(27 "Margin" user)
		(31 "F.CrtYd" user "Package Geometry/Place Bound Top")
		(29 "B.CrtYd" user "Package Geometry/Place Bound Bottom")
		(35 "F.Fab" user "Ref Des/Assembly Top")
		(33 "B.Fab" user "Ref Des/Assembly Bottom")
	)
	(footprint ""
		(layer "B.Cu")
		(at 270.645128 -244.08511 180)
		(property "Reference" "R380"
			(at 0 0 0)
			(layer "B.SilkS")
			(hide yes)
			(effects
				(font
					(size 1.27 1.27)
				)
				(justify mirror)
			)
		)
		(property "Value" ""
			(at 0 0 0)
			(layer "B.Fab")
			(effects
				(font
					(size 1.27 1.27)
				)
				(justify mirror)
			)
		)
		(duplicate_pad_numbers_are_jumpers no)
		(fp_line
			(start 0.7874 0.4064)
			(end 0.7874 -0.4064)
			(stroke
				(width 0.1524)
				(type default)
			)
			(layer "B.SilkS")
		)
		(fp_line
			(start 0.7874 -0.4064)
			(end -0.7874 -0.4064)
			(stroke
				(width 0.1524)
				(type default)
			)
			(layer "B.SilkS")
		)
		(fp_line
			(start -0.7874 0.4064)
			(end 0.7874 0.4064)
			(stroke
				(width 0.1524)
				(type default)
			)
			(layer "B.SilkS")
		)
		(fp_line
			(start -0.7874 -0.4064)
			(end -0.7874 0.4064)
			(stroke
				(width 0.1524)
				(type default)
			)
			(layer "B.SilkS")
		)
		(fp_line
			(start 0.67945 0.3048)
			(end 0.67945 -0.305054)
			(stroke
				(width 0.1)
				(type default)
			)
			(layer "B.Fab")
		)
		(fp_line
			(start 0.67945 -0.305054)
			(end 0.12065 -0.305054)
			(stroke
				(width 0.1)
				(type default)
			)
			(layer "B.Fab")
		)
		(fp_line
			(start 0.12065 0.3048)
			(end 0.67945 0.3048)
			(stroke
				(width 0.1)
				(type default)
			)
			(layer "B.Fab")
		)
		(fp_line
			(start 0.12065 0.2794)
			(end 0.12065 0.3048)
			(stroke
				(width 0.1)
				(type default)
			)
			(layer "B.Fab")
		)
		(fp_line
			(start 0.12065 -0.2794)
			(end -0.12065 -0.2794)
			(stroke
				(width 0.1)
				(type default)
			)
			(layer "B.Fab")
		)
		(fp_line
			(start 0.12065 -0.305054)
			(end 0.12065 -0.2794)
			(stroke
				(width 0.1)
				(type default)
			)
			(layer "B.Fab")
		)
		(fp_line
			(start -0.120396 0.3048)
			(end -0.120396 0.2794)
			(stroke
				(width 0.1)
				(type default)
			)
			(layer "B.Fab")
		)
		(fp_line
			(start -0.120396 0.2794)
			(end 0.12065 0.2794)
			(stroke
				(width 0.1)
				(type default)
			)
			(layer "B.Fab")
		)
		(fp_line
			(start -0.12065 -0.2794)
			(end -0.12065 -0.3048)
			(stroke
				(width 0.1)
				(type default)
			)
			(layer "B.Fab")
		)
		(fp_line
			(start -0.12065 -0.3048)
			(end -0.67945 -0.3048)
			(stroke
				(width 0.1)
				(type default)
			)
			(layer "B.Fab")
		)
		(fp_line
			(start -0.67945 0.3048)
			(end -0.120396 0.3048)
			(stroke
				(width 0.1)
				(type default)
			)
			(layer "B.Fab")
		)
		(fp_line
			(start -0.67945 -0.3048)
			(end -0.67945 0.3048)
			(stroke
				(width 0.1)
				(type default)
			)
			(layer "B.Fab")
		)
		(pad "1" smd circle
			(at 0.40005 0)
			(size 0 0)
			(layers "B.Cu" "B.Mask" "B.Paste")
			(net "M_F_CPU0_ALERT_N")
		)
		(pad "2" smd circle
			(at -0.40005 0)
			(size 0 0)
			(layers "B.Cu" "B.Mask" "B.Paste")
			(net "M_F_CPU0_ALERT_R_N")
		)
	)
	(footprint ""
		(layer "B.Cu")
		(at 154.577288 -8.68045 -90)
		(property "Reference" "R6069"
			(at 0 0 90)
			(layer "B.SilkS")
			(hide yes)
			(effects
				(font
					(size 1.27 1.27)
				)
				(justify mirror)
			)
		)
		(property "Value" ""
			(at 0 0 90)
			(layer "B.Fab")
			(effects
				(font
					(size 1.27 1.27)
				)
				(justify mirror)
			)
		)
		(duplicate_pad_numbers_are_jumpers no)
		(fp_line
			(start -0.7874 0.4064)
			(end 0.7874 0.4064)
			(stroke
				(width 0.1524)
				(type default)
			)
			(layer "B.SilkS")
		)
		(fp_line
			(start 0.7874 0.4064)
			(end 0.7874 -0.4064)
			(stroke
				(width 0.1524)
				(type default)
			)
			(layer "B.SilkS")
		)
		(fp_line
			(start -0.7874 -0.4064)
			(end -0.7874 0.4064)
			(stroke
				(width 0.1524)
				(type default)
			)
			(layer "B.SilkS")
		)
		(fp_line
			(start 0.7874 -0.4064)
			(end -0.7874 -0.4064)
			(stroke
				(width 0.1524)
				(type default)
			)
			(layer "B.SilkS")
		)
		(fp_line
			(start -0.67945 0.3048)
			(end -0.120396 0.3048)
			(stroke
				(width 0.1)
				(type default)
			)
			(layer "B.Fab")
		)
		(fp_line
			(start -0.120396 0.3048)
			(end -0.120396 0.2794)
			(stroke
				(width 0.1)
				(type default)
			)
			(layer "B.Fab")
		)
		(fp_line
			(start 0.12065 0.3048)
			(end 0.67945 0.3048)
			(stroke
				(width 0.1)
				(type default)
			)
			(layer "B.Fab")
		)
		(fp_line
			(start 0.67945 0.3048)
			(end 0.67945 -0.305054)
			(stroke
				(width 0.1)
				(type default)
			)
			(layer "B.Fab")
		)
		(fp_line
			(start -0.120396 0.2794)
			(end 0.12065 0.2794)
			(stroke
				(width 0.1)
				(type default)
			)
			(layer "B.Fab")
		)
		(fp_line
			(start 0.12065 0.2794)
			(end 0.12065 0.3048)
			(stroke
				(width 0.1)
				(type default)
			)
			(layer "B.Fab")
		)
		(fp_line
			(start -0.12065 -0.2794)
			(end -0.12065 -0.3048)
			(stroke
				(width 0.1)
				(type default)
			)
			(layer "B.Fab")
		)
		(fp_line
			(start 0.12065 -0.2794)
			(end -0.12065 -0.2794)
			(stroke
				(width 0.1)
				(type default)
			)
			(layer "B.Fab")
		)
		(fp_line
			(start -0.67945 -0.3048)
			(end -0.67945 0.3048)
			(stroke
				(width 0.1)
				(type default)
			)
			(layer "B.Fab")
		)
		(fp_line
			(start -0.12065 -0.3048)
			(end -0.67945 -0.3048)
			(stroke
				(width 0.1)
				(type default)
			)
			(layer "B.Fab")
		)
		(fp_line
			(start 0.12065 -0.305054)
			(end 0.12065 -0.2794)
			(stroke
				(width 0.1)
				(type default)
			)
			(layer "B.Fab")
		)
		(fp_line
			(start 0.67945 -0.305054)
			(end 0.12065 -0.305054)
			(stroke
				(width 0.1)
				(type default)
			)
			(layer "B.Fab")
		)
		(pad "1" smd rect
			(at 0.40005 0 270)
			(size 0.4572 0.508)
			(layers "B.Cu" "B.Mask" "B.Paste")
			(net "JTAG_SCM_TDI_R")
		)
		(pad "2" smd rect
			(at -0.40005 0 270)
			(size 0.4572 0.508)
			(layers "B.Cu" "B.Mask" "B.Paste")
			(net "JTAG_SCM_TDO")
		)
	)
	(footprint ""
		(layer "B.Cu")
		(at 375.331482 -147.741132 180)
		(property "Reference" "PC463"
			(at 0 0 0)
			(layer "B.SilkS")
			(hide yes)
			(effects
				(font
					(size 1.27 1.27)
				)
				(justify mirror)
			)
		)
		(property "Value" ""
			(at 0 0 0)
			(layer "B.Fab")
			(effects
				(font
					(size 1.27 1.27)
				)
				(justify mirror)
			)
		)
		(duplicate_pad_numbers_are_jumpers no)
		(fp_line
			(start 0.7874 0.4064)
			(end 0.7874 -0.4064)
			(stroke
				(width 0.1524)
				(type default)
			)
			(layer "B.SilkS")
		)
		(fp_line
			(start 0.7874 -0.4064)
			(end -0.7874 -0.4064)
			(stroke
				(width 0.1524)
				(type default)
			)
			(layer "B.SilkS")
		)
		(fp_line
			(start -0.7874 0.4064)
			(end 0.7874 0.4064)
			(stroke
				(width 0.1524)
				(type default)
			)
			(layer "B.SilkS")
		)
		(fp_line
			(start -0.7874 -0.4064)
			(end -0.7874 0.4064)
			(stroke
				(width 0.1524)
				(type default)
			)
			(layer "B.SilkS")
		)
		(fp_line
			(start 0.67945 0.3048)
			(end 0.67945 -0.305054)
			(stroke
				(width 0.1)
				(type default)
			)
			(layer "B.Fab")
		)
		(fp_line
			(start 0.67945 -0.305054)
			(end 0.12065 -0.305054)
			(stroke
				(width 0.1)
				(type default)
			)
			(layer "B.Fab")
		)
		(fp_line
			(start 0.12065 0.3048)
			(end 0.67945 0.3048)
			(stroke
				(width 0.1)
				(type default)
			)
			(layer "B.Fab")
		)
		(fp_line
			(start 0.12065 0.2794)
			(end 0.12065 0.3048)
			(stroke
				(width 0.1)
				(type default)
			)
			(layer "B.Fab")
		)
		(fp_line
			(start 0.12065 -0.2794)
			(end -0.12065 -0.2794)
			(stroke
				(width 0.1)
				(type default)
			)
			(layer "B.Fab")
		)
		(fp_line
			(start 0.12065 -0.305054)
			(end 0.12065 -0.2794)
			(stroke
				(width 0.1)
				(type default)
			)
			(layer "B.Fab")
		)
		(fp_line
			(start -0.120396 0.3048)
			(end -0.120396 0.2794)
			(stroke
				(width 0.1)
				(type default)
			)
			(layer "B.Fab")
		)
		(fp_line
			(start -0.120396 0.2794)
			(end 0.12065 0.2794)
			(stroke
				(width 0.1)
				(type default)
			)
			(layer "B.Fab")
		)
		(fp_line
			(start -0.12065 -0.2794)
			(end -0.12065 -0.3048)
			(stroke
				(width 0.1)
				(type default)
			)
			(layer "B.Fab")
		)
		(fp_line
			(start -0.12065 -0.3048)
			(end -0.67945 -0.3048)
			(stroke
				(width 0.1)
				(type default)
			)
			(layer "B.Fab")
		)
		(fp_line
			(start -0.67945 0.3048)
			(end -0.120396 0.3048)
			(stroke
				(width 0.1)
				(type default)
			)
			(layer "B.Fab")
		)
		(fp_line
			(start -0.67945 -0.3048)
			(end -0.67945 0.3048)
			(stroke
				(width 0.1)
				(type default)
			)
			(layer "B.Fab")
		)
		(pad "1" smd circle
			(at 0.40005 0)
			(size 0 0)
			(layers "B.Cu" "B.Mask" "B.Paste")
			(net "VSENSE_PVDDCR_CPU0_P0_VSEN0")
		)
		(pad "2" smd circle
			(at -0.40005 0)
			(size 0 0)
			(layers "B.Cu" "B.Mask" "B.Paste")
			(net "VSENSE_VSS_SENSE_A_P0")
		)
	)
	(footprint ""
		(layer "B.Cu")
		(at 359.740454 -246.06631 90)
		(property "Reference" "C251"
			(at 0 0 90)
			(layer "B.SilkS")
			(hide yes)
			(effects
				(font
					(size 1.27 1.27)
				)
				(justify mirror)
			)
		)
		(property "Value" ""
			(at 0 0 90)
			(layer "B.Fab")
			(effects
				(font
					(size 1.27 1.27)
				)
				(justify mirror)
			)
		)
		(duplicate_pad_numbers_are_jumpers no)
		(fp_line
			(start 0.7874 -0.4064)
			(end -0.7874 -0.4064)
			(stroke
				(width 0.1524)
				(type default)
			)
			(layer "B.SilkS")
		)
		(fp_line
			(start -0.7874 -0.4064)
			(end -0.7874 0.4064)
			(stroke
				(width 0.1524)
				(type default)
			)
			(layer "B.SilkS")
		)
		(fp_line
			(start 0.7874 0.4064)
			(end 0.7874 -0.4064)
			(stroke
				(width 0.1524)
				(type default)
			)
			(layer "B.SilkS")
		)
		(fp_line
			(start -0.7874 0.4064)
			(end 0.7874 0.4064)
			(stroke
				(width 0.1524)
				(type default)
			)
			(layer "B.SilkS")
		)
		(fp_line
			(start 0.67945 -0.305054)
			(end 0.12065 -0.305054)
			(stroke
				(width 0.1)
				(type default)
			)
			(layer "B.Fab")
		)
		(fp_line
			(start 0.12065 -0.305054)
			(end 0.12065 -0.2794)
			(stroke
				(width 0.1)
				(type default)
			)
			(layer "B.Fab")
		)
		(fp_line
			(start -0.12065 -0.3048)
			(end -0.67945 -0.3048)
			(stroke
				(width 0.1)
				(type default)
			)
			(layer "B.Fab")
		)
		(fp_line
			(start -0.67945 -0.3048)
			(end -0.67945 0.3048)
			(stroke
				(width 0.1)
				(type default)
			)
			(layer "B.Fab")
		)
		(fp_line
			(start 0.12065 -0.2794)
			(end -0.12065 -0.2794)
			(stroke
				(width 0.1)
				(type default)
			)
			(layer "B.Fab")
		)
		(fp_line
			(start -0.12065 -0.2794)
			(end -0.12065 -0.3048)
			(stroke
				(width 0.1)
				(type default)
			)
			(layer "B.Fab")
		)
		(fp_line
			(start 0.12065 0.2794)
			(end 0.12065 0.3048)
			(stroke
				(width 0.1)
				(type default)
			)
			(layer "B.Fab")
		)
		(fp_line
			(start -0.120396 0.2794)
			(end 0.12065 0.2794)
			(stroke
				(width 0.1)
				(type default)
			)
			(layer "B.Fab")
		)
		(fp_line
			(start 0.67945 0.3048)
			(end 0.67945 -0.305054)
			(stroke
				(width 0.1)
				(type default)
			)
			(layer "B.Fab")
		)
		(fp_line
			(start 0.12065 0.3048)
			(end 0.67945 0.3048)
			(stroke
				(width 0.1)
				(type default)
			)
			(layer "B.Fab")
		)
		(fp_line
			(start -0.120396 0.3048)
			(end -0.120396 0.2794)
			(stroke
				(width 0.1)
				(type default)
			)
			(layer "B.Fab")
		)
		(fp_line
			(start -0.67945 0.3048)
			(end -0.120396 0.3048)
			(stroke
				(width 0.1)
				(type default)
			)
			(layer "B.Fab")
		)
		(pad "1" smd circle
			(at 0.40005 0 270)
			(size 0 0)
			(layers "B.Cu" "B.Mask" "B.Paste")
			(net "PVDDCR_CPU0_P0")
		)
		(pad "2" smd circle
			(at -0.40005 0 270)
			(size 0 0)
			(layers "B.Cu" "B.Mask" "B.Paste")
			(net "GND")
		)
	)
	(footprint ""
		(layer "B.Cu")
		(at 176.072292 -192.66027)
		(property "Reference" "C533"
			(at 0 0 0)
			(layer "B.SilkS")
			(hide yes)
			(effects
				(font
					(size 1.27 1.27)
				)
				(justify mirror)
			)
		)
		(property "Value" ""
			(at 0 0 0)
			(layer "B.Fab")
			(effects
				(font
					(size 1.27 1.27)
				)
				(justify mirror)
			)
		)
		(duplicate_pad_numbers_are_jumpers no)
		(fp_line
			(start -1.524 -0.762)
			(end -1.524 0.762)
			(stroke
				(width 0.1524)
				(type default)
			)
			(layer "B.SilkS")
		)
		(fp_line
			(start -1.524 0.762)
			(end 1.524 0.762)
			(stroke
				(width 0.1524)
				(type default)
			)
			(layer "B.SilkS")
		)
		(fp_line
			(start 1.524 -0.762)
			(end -1.524 -0.762)
			(stroke
				(width 0.1524)
				(type default)
			)
			(layer "B.SilkS")
		)
		(fp_line
			(start 1.524 0.762)
			(end 1.524 -0.762)
			(stroke
				(width 0.1524)
				(type default)
			)
			(layer "B.SilkS")
		)
		(fp_line
			(start -1.1049 -0.724916)
			(end 1.1049 -0.724916)
			(stroke
				(width 0.1)
				(type default)
			)
			(layer "B.Fab")
		)
		(fp_line
			(start -1.1049 0.724916)
			(end -1.1049 -0.724916)
			(stroke
				(width 0.1)
				(type default)
			)
			(layer "B.Fab")
		)
		(fp_line
			(start 1.1049 -0.724916)
			(end 1.1049 0.724916)
			(stroke
				(width 0.1)
				(type default)
			)
			(layer "B.Fab")
		)
		(fp_line
			(start 1.1049 0.724916)
			(end -1.1049 0.724916)
			(stroke
				(width 0.1)
				(type default)
			)
			(layer "B.Fab")
		)
		(pad "1" smd rect
			(at 0.889 0)
			(size 1.016 1.27)
			(layers "B.Cu" "B.Mask" "B.Paste")
			(net "P12V_MEM_CPU1")
		)
		(pad "2" smd rect
			(at -0.889 0)
			(size 1.016 1.27)
			(layers "B.Cu" "B.Mask" "B.Paste")
			(net "GND")
		)
	)
	(footprint ""
		(layer "B.Cu")
		(at 333.945992 -395.43228)
		(property "Reference" "C620"
			(at 0 0 0)
			(layer "B.SilkS")
			(hide yes)
			(effects
				(font
					(size 1.27 1.27)
				)
				(justify mirror)
			)
		)
		(property "Value" ""
			(at 0 0 0)
			(layer "B.Fab")
			(effects
				(font
					(size 1.27 1.27)
				)
				(justify mirror)
			)
		)
		(duplicate_pad_numbers_are_jumpers no)
		(fp_line
			(start -0.299974 -0.150114)
			(end -0.299974 0.150114)
			(stroke
				(width 0.1)
				(type default)
			)
			(layer "B.Fab")
		)
		(fp_line
			(start -0.299974 0.150114)
			(end 0.299974 0.150114)
			(stroke
				(width 0.1)
				(type default)
			)
			(layer "B.Fab")
		)
		(fp_line
			(start 0.299974 -0.150114)
			(end -0.299974 -0.150114)
			(stroke
				(width 0.1)
				(type default)
			)
			(layer "B.Fab")
		)
		(fp_line
			(start 0.299974 0.150114)
			(end 0.299974 -0.150114)
			(stroke
				(width 0.1)
				(type default)
			)
			(layer "B.Fab")
		)
		(pad "1" smd rect
			(at 0.2667 0 180)
			(size 0.3048 0.381)
			(layers "B.Cu" "B.Mask" "B.Paste")
			(net "P0V9_CPU0_RT1_2A")
		)
		(pad "2" smd rect
			(at -0.2667 0 180)
			(size 0.3048 0.381)
			(layers "B.Cu" "B.Mask" "B.Paste")
			(net "GND")
		)
	)
	(footprint ""
		(layer "B.Cu")
		(at 51.734974 -416.929316)
		(property "Reference" "C2076"
			(at 0 0 0)
			(layer "B.SilkS")
			(hide yes)
			(effects
				(font
					(size 1.27 1.27)
				)
				(justify mirror)
			)
		)
		(property "Value" ""
			(at 0 0 0)
			(layer "B.Fab")
			(effects
				(font
					(size 1.27 1.27)
				)
				(justify mirror)
			)
		)
		(duplicate_pad_numbers_are_jumpers no)
		(fp_line
			(start -0.299974 -0.150114)
			(end -0.299974 0.150114)
			(stroke
				(width 0.1)
				(type default)
			)
			(layer "B.Fab")
		)
		(fp_line
			(start -0.299974 0.150114)
			(end 0.299974 0.150114)
			(stroke
				(width 0.1)
				(type default)
			)
			(layer "B.Fab")
		)
		(fp_line
			(start 0.299974 -0.150114)
			(end -0.299974 -0.150114)
			(stroke
				(width 0.1)
				(type default)
			)
			(layer "B.Fab")
		)
		(fp_line
			(start 0.299974 0.150114)
			(end 0.299974 -0.150114)
			(stroke
				(width 0.1)
				(type default)
			)
			(layer "B.Fab")
		)
		(pad "1" smd rect
			(at 0.2667 0 180)
			(size 0.3048 0.381)
			(layers "B.Cu" "B.Mask" "B.Paste")
			(net "P3E_CPU1_P5_TX_C_DN<0>")
		)
		(pad "2" smd rect
			(at -0.2667 0 180)
			(size 0.3048 0.381)
			(layers "B.Cu" "B.Mask" "B.Paste")
			(net "P3E_CPU1_P5_TX_DN<0>")
		)
	)
)
